(kicad_pcb
	(version 20260206)
	(generator "pcbnew")
	(generator_version "10.0")
	(general
		(thickness 1.6)
		(legacy_teardrops no)
	)
	(paper "A4")
	(title_block
		(title "Bryce Canyon_Front Panel_16369-1_OCP.brd")
		(comment 1 "Bryce Canyon / footprints 8-14 of 154")
	)
	(layers
		(0 "F.Cu" signal "TOP")
		(4 "In1.Cu" signal "L2GND")
		(6 "In2.Cu" signal "L3VCC")
		(2 "B.Cu" signal "BOTTOM")
		(9 "F.Adhes" user "F.Adhesive")
		(11 "B.Adhes" user "B.Adhesive")
		(13 "F.Paste" user "Package Geometry/Pastemask Top")
		(15 "B.Paste" user "Package Geometry/Pastemask Bottom")
		(5 "F.SilkS" user "Ref Des/Silkscreen Top")
		(7 "B.SilkS" user "Ref Des/Silkscreen Bottom")
		(1 "F.Mask" user "Board Geometry/Soldermask Top")
		(3 "B.Mask" user "Board Geometry/Soldermask Bottom")
		(17 "Dwgs.User" user "User.Drawings")
		(19 "Cmts.User" user "User.Comments")
		(21 "Eco1.User" user "User.Eco1")
		(23 "Eco2.User" user "User.Eco2")
		(25 "Edge.Cuts" user "Board Geometry/Outline")
		(27 "Margin" user)
		(31 "F.CrtYd" user "Package Geometry/Place Bound Top")
		(29 "B.CrtYd" user "Package Geometry/Place Bound Bottom")
		(35 "F.Fab" user "Ref Des/Assembly Top")
		(33 "B.Fab" user "Ref Des/Assembly Bottom")
	)
	(footprint ""
		(layer "F.Cu")
		(at 3.8862 -72.5551 180)
		(property "Reference" "D7"
			(at 0 0 180)
			(layer "F.SilkS")
			(hide yes)
			(effects
				(font
					(size 1.27 1.27)
				)
			)
		)
		(property "Value" "PESD5V0X1UAB-GP"
			(at 0 -4.690618 180)
			(unlocked yes)
			(layer "F.Fab")
			(hide yes)
			(effects
				(font
					(size 1.016 1.016)
					(thickness 0.1524)
				)
			)
		)
		(property "Device Type" "SOD523AKH26"
			(at 0 -6.214618 180)
			(unlocked yes)
			(layer "F.Fab")
			(hide yes)
			(effects
				(font
					(size 1.016 1.016)
					(thickness 0.1524)
				)
			)
		)
		(duplicate_pad_numbers_are_jumpers no)
		(fp_line
			(start 0.5334 1.524)
			(end -0.5334 1.524)
			(stroke
				(width 0.1524)
				(type default)
			)
			(layer "F.SilkS")
		)
		(fp_line
			(start 0.5334 -1.4478)
			(end 0.5334 1.524)
			(stroke
				(width 0.1524)
				(type default)
			)
			(layer "F.SilkS")
		)
		(fp_line
			(start 0.4064 1.651)
			(end -0.4064 1.651)
			(stroke
				(width 0.4064)
				(type default)
			)
			(layer "F.SilkS")
		)
		(fp_line
			(start -0.5334 1.524)
			(end -0.5334 -1.4478)
			(stroke
				(width 0.1524)
				(type default)
			)
			(layer "F.SilkS")
		)
		(fp_line
			(start -0.5334 -1.4478)
			(end 0.5334 -1.4478)
			(stroke
				(width 0.1524)
				(type default)
			)
			(layer "F.SilkS")
		)
		(fp_rect
			(start -0.6096 1.8542)
			(end 0.6096 -1.524)
			(stroke
				(width 0)
				(type default)
			)
			(fill no)
			(layer "F.CrtYd")
		)
		(fp_poly
			(pts
				(xy -0.6096 -1.524) (xy 0.6096 -1.524) (xy 0.6096 1.8542) (xy -0.6096 1.8542)
			)
			(stroke
				(width 0)
				(type default)
			)
			(fill no)
			(layer "F.Fab")
		)
		(pad "A" smd rect
			(at 0 -0.762 180)
			(size 0.5588 1.016)
			(layers "F.Cu" "F.Mask" "F.Paste")
			(net "GND")
		)
		(pad "K" smd rect
			(at 0 0.762 180)
			(size 0.5588 1.016)
			(layers "F.Cu" "F.Mask" "F.Paste")
			(net "PWR_BTN_A")
		)
	)
	(footprint ""
		(layer "F.Cu")
		(at 31.70301 -9.903714 180)
		(property "Reference" "U20"
			(at 0 0 180)
			(layer "F.SilkS")
			(hide yes)
			(effects
				(font
					(size 1.27 1.27)
				)
			)
		)
		(property "Value" "SN74LVC1G74DCUT-GP"
			(at 0 -11.1252 180)
			(unlocked yes)
			(layer "F.Fab")
			(hide yes)
			(effects
				(font
					(size 1.016 1.016)
					(thickness 0.1524)
				)
			)
		)
		(property "Device Type" "SSOIC8-4H36"
			(at 0 -12.6492 180)
			(unlocked yes)
			(layer "F.Fab")
			(hide yes)
			(effects
				(font
					(size 1.016 1.016)
					(thickness 0.1524)
				)
			)
		)
		(duplicate_pad_numbers_are_jumpers no)
		(fp_line
			(start 1.2573 2.1844)
			(end -1.2573 2.1844)
			(stroke
				(width 0.1524)
				(type default)
			)
			(layer "F.SilkS")
		)
		(fp_line
			(start 1.2573 -2.1844)
			(end 1.2573 2.1844)
			(stroke
				(width 0.1524)
				(type default)
			)
			(layer "F.SilkS")
		)
		(fp_line
			(start -0.9017 -0.0381)
			(end -1.2065 0.2667)
			(stroke
				(width 0.1524)
				(type default)
			)
			(layer "F.SilkS")
		)
		(fp_line
			(start -1.2065 0.2667)
			(end -1.27 0.2667)
			(stroke
				(width 0.1524)
				(type default)
			)
			(layer "F.SilkS")
		)
		(fp_line
			(start -1.2192 -0.3556)
			(end -0.9017 -0.0381)
			(stroke
				(width 0.1524)
				(type default)
			)
			(layer "F.SilkS")
		)
		(fp_line
			(start -1.2573 2.1844)
			(end -1.2573 -2.1844)
			(stroke
				(width 0.1524)
				(type default)
			)
			(layer "F.SilkS")
		)
		(fp_line
			(start -1.2573 -0.3556)
			(end -1.2192 -0.3556)
			(stroke
				(width 0.1524)
				(type default)
			)
			(layer "F.SilkS")
		)
		(fp_line
			(start -1.2573 -2.1844)
			(end 1.2573 -2.1844)
			(stroke
				(width 0.1524)
				(type default)
			)
			(layer "F.SilkS")
		)
		(fp_line
			(start -1.2954 0.4572)
			(end -1.2954 2.159)
			(stroke
				(width 0.4064)
				(type default)
			)
			(layer "F.SilkS")
		)
		(fp_poly
			(pts
				(xy -1.5113 2.4384) (xy 1.5113 2.4384) (xy 1.5113 -2.4384) (xy -1.5113 -2.4384)
			)
			(stroke
				(width 0)
				(type default)
			)
			(fill no)
			(layer "F.CrtYd")
		)
		(fp_poly
			(pts
				(xy -1.5113 -2.4384) (xy 1.5113 -2.4384) (xy 1.5113 2.4384) (xy -1.5113 2.4384)
			)
			(stroke
				(width 0)
				(type default)
			)
			(fill no)
			(layer "F.Fab")
		)
		(pad "1" smd rect
			(at -0.75057 1.1684 180)
			(size 0.3048 1.524)
			(layers "F.Cu" "F.Mask" "F.Paste")
			(net "DEBUG_HDR_B_UART_SEL")
		)
		(pad "2" smd rect
			(at -0.25019 1.1684 180)
			(size 0.3048 1.524)
			(layers "F.Cu" "F.Mask" "F.Paste")
			(net "D_FLIP_B_D")
		)
		(pad "3" smd rect
			(at 0.25019 1.1684 180)
			(size 0.3048 1.524)
			(layers "F.Cu" "F.Mask" "F.Paste")
			(net "D_FLIP_B_Q#")
		)
		(pad "4" smd rect
			(at 0.75057 1.1684 180)
			(size 0.3048 1.524)
			(layers "F.Cu" "F.Mask" "F.Paste")
			(net "GND")
		)
		(pad "5" smd rect
			(at 0.75057 -1.1684 180)
			(size 0.3048 1.524)
			(layers "F.Cu" "F.Mask" "F.Paste")
			(net "UART_SEL_B_MUX")
		)
		(pad "6" smd rect
			(at 0.25019 -1.1684 180)
			(size 0.3048 1.524)
			(layers "F.Cu" "F.Mask" "F.Paste")
			(net "D_FLIP_CLR_B#")
		)
		(pad "7" smd rect
			(at -0.25019 -1.1684 180)
			(size 0.3048 1.524)
			(layers "F.Cu" "F.Mask" "F.Paste")
			(net "D_FLIP_PRE_B#")
		)
		(pad "8" smd rect
			(at -0.75057 -1.1684 180)
			(size 0.3048 1.524)
			(layers "F.Cu" "F.Mask" "F.Paste")
			(net "P3V3_STBY_B")
		)
	)
	(footprint ""
		(layer "F.Cu")
		(at 42.917364 -21.64842 180)
		(property "Reference" "C24"
			(at 0 0 180)
			(layer "F.SilkS")
			(hide yes)
			(effects
				(font
					(size 1.27 1.27)
				)
			)
		)
		(property "Value" "SCD1U16V2KX-3GP"
			(at 1.1811 -2.7051 180)
			(unlocked yes)
			(layer "F.Fab")
			(hide yes)
			(effects
				(font
					(size 1.016 1.016)
					(thickness 0.1524)
				)
			)
		)
		(property "Device Type" "C402H22"
			(at 1.1811 -4.2291 180)
			(unlocked yes)
			(layer "F.Fab")
			(hide yes)
			(effects
				(font
					(size 1.016 1.016)
					(thickness 0.1524)
				)
			)
		)
		(duplicate_pad_numbers_are_jumpers no)
		(fp_rect
			(start -0.4318 0.9525)
			(end 0.4318 -0.9525)
			(stroke
				(width 0)
				(type default)
			)
			(fill no)
			(layer "F.CrtYd")
		)
		(fp_rect
			(start -0.4318 0.9525)
			(end 0.4318 -0.9525)
			(stroke
				(width 0)
				(type default)
			)
			(fill no)
			(layer "F.Fab")
		)
		(pad "1" smd custom
			(at 0 -0.4445 180)
			(size 0.1524 0.1524)
			(layers "F.Cu" "F.Mask" "F.Paste")
			(net "P3V3_STBY_B")
			(options
				(clearance outline)
				(anchor circle)
			)
			(primitives
				(gr_poly
					(pts
						(arc
							(start 0.3048 -0.2032)
							(mid 0.275042 -0.275042)
							(end 0.2032 -0.3048)
						)
						(arc
							(start -0.2032 -0.3048)
							(mid -0.275042 -0.275042)
							(end -0.3048 -0.2032)
						)
						(arc
							(start -0.3048 0.2032)
							(mid -0.275042 0.275042)
							(end -0.2032 0.3048)
						)
						(arc
							(start 0.2032 0.3048)
							(mid 0.275042 0.275042)
							(end 0.3048 0.2032)
						)
					)
					(width 0)
					(fill yes)
				)
			)
		)
		(pad "2" smd custom
			(at 0 0.4445 180)
			(size 0.1524 0.1524)
			(layers "F.Cu" "F.Mask" "F.Paste")
			(net "GND")
			(options
				(clearance outline)
				(anchor circle)
			)
			(primitives
				(gr_poly
					(pts
						(arc
							(start 0.3048 -0.2032)
							(mid 0.275042 -0.275042)
							(end 0.2032 -0.3048)
						)
						(arc
							(start -0.2032 -0.3048)
							(mid -0.275042 -0.275042)
							(end -0.3048 -0.2032)
						)
						(arc
							(start -0.3048 0.2032)
							(mid -0.275042 0.275042)
							(end -0.2032 0.3048)
						)
						(arc
							(start 0.2032 0.3048)
							(mid 0.275042 0.275042)
							(end 0.3048 0.2032)
						)
					)
					(width 0)
					(fill yes)
				)
			)
		)
	)
	(footprint ""
		(layer "F.Cu")
		(at 3.0734 -21.082)
		(property "Reference" "R6"
			(at 0 0 0)
			(layer "F.SilkS")
			(hide yes)
			(effects
				(font
					(size 1.27 1.27)
				)
			)
		)
		(property "Value" "4K7R2F-GP"
			(at 0.064008 -4.679696 0)
			(unlocked yes)
			(layer "F.Fab")
			(hide yes)
			(effects
				(font
					(size 2.54 2.54)
					(thickness 0.381)
				)
			)
		)
		(property "Device Type" "R402H16"
			(at 0.064008 -6.203696 0)
			(unlocked yes)
			(layer "F.Fab")
			(hide yes)
			(effects
				(font
					(size 2.54 2.54)
					(thickness 0.381)
				)
			)
		)
		(duplicate_pad_numbers_are_jumpers no)
		(fp_line
			(start -0.508 -0.9398)
			(end -0.508 0.9398)
			(stroke
				(width 0.1524)
				(type default)
			)
			(layer "F.SilkS")
		)
		(fp_line
			(start 0.508 -0.9398)
			(end -0.508 -0.9398)
			(stroke
				(width 0.1524)
				(type default)
			)
			(layer "F.SilkS")
		)
		(fp_rect
			(start -0.508 0.9398)
			(end 0.508 -0.9398)
			(stroke
				(width 0)
				(type default)
			)
			(fill no)
			(layer "F.CrtYd")
		)
		(fp_rect
			(start -0.508 0.9398)
			(end 0.508 -0.9398)
			(stroke
				(width 0)
				(type default)
			)
			(fill no)
			(layer "F.Fab")
		)
		(pad "1" smd custom
			(at 0 -0.4445)
			(size 0.1397 0.1397)
			(layers "F.Cu" "F.Mask" "F.Paste")
			(net "P3V3_STBY_A")
			(options
				(clearance outline)
				(anchor circle)
			)
			(primitives
				(gr_poly
					(pts
						(arc
							(start -0.1778 -0.2794)
							(mid -0.249642 -0.249642)
							(end -0.2794 -0.1778)
						)
						(arc
							(start -0.2794 0.1778)
							(mid -0.249642 0.249642)
							(end -0.1778 0.2794)
						)
						(arc
							(start 0.1778 0.2794)
							(mid 0.249642 0.249642)
							(end 0.2794 0.1778)
						)
						(arc
							(start 0.2794 -0.1778)
							(mid 0.249642 -0.249642)
							(end 0.1778 -0.2794)
						)
					)
					(width 0)
					(fill yes)
				)
			)
		)
		(pad "2" smd custom
			(at 0 0.4445)
			(size 0.1397 0.1397)
			(layers "F.Cu" "F.Mask" "F.Paste")
			(net "I2C_DEBUG_A_SCL")
			(options
				(clearance outline)
				(anchor circle)
			)
			(primitives
				(gr_poly
					(pts
						(arc
							(start -0.1778 -0.2794)
							(mid -0.249642 -0.249642)
							(end -0.2794 -0.1778)
						)
						(arc
							(start -0.2794 0.1778)
							(mid -0.249642 0.249642)
							(end -0.1778 0.2794)
						)
						(arc
							(start 0.1778 0.2794)
							(mid 0.249642 0.249642)
							(end 0.2794 0.1778)
						)
						(arc
							(start 0.2794 -0.1778)
							(mid 0.249642 -0.249642)
							(end 0.1778 -0.2794)
						)
					)
					(width 0)
					(fill yes)
				)
			)
		)
	)
	(footprint ""
		(layer "F.Cu")
		(at 12.487148 -39.158418 90)
		(property "Reference" "R21"
			(at 0 0 90)
			(layer "F.SilkS")
			(hide yes)
			(effects
				(font
					(size 1.27 1.27)
				)
			)
		)
		(property "Value" "22KR2F-GP"
			(at 0.064008 -4.679696 90)
			(unlocked yes)
			(layer "F.Fab")
			(hide yes)
			(effects
				(font
					(size 2.54 2.54)
					(thickness 0.381)
				)
			)
		)
		(property "Device Type" "R402H16"
			(at 0.064008 -6.203696 90)
			(unlocked yes)
			(layer "F.Fab")
			(hide yes)
			(effects
				(font
					(size 2.54 2.54)
					(thickness 0.381)
				)
			)
		)
		(duplicate_pad_numbers_are_jumpers no)
		(fp_line
			(start 0.508 -0.9398)
			(end -0.508 -0.9398)
			(stroke
				(width 0.1524)
				(type default)
			)
			(layer "F.SilkS")
		)
		(fp_line
			(start -0.508 -0.9398)
			(end -0.508 0.9398)
			(stroke
				(width 0.1524)
				(type default)
			)
			(layer "F.SilkS")
		)
		(fp_rect
			(start -0.508 0.9398)
			(end 0.508 -0.9398)
			(stroke
				(width 0)
				(type default)
			)
			(fill no)
			(layer "F.CrtYd")
		)
		(fp_rect
			(start -0.508 0.9398)
			(end 0.508 -0.9398)
			(stroke
				(width 0)
				(type default)
			)
			(fill no)
			(layer "F.Fab")
		)
		(pad "1" smd custom
			(at 0 -0.4445 90)
			(size 0.1397 0.1397)
			(layers "F.Cu" "F.Mask" "F.Paste")
			(net "P3V3_STBY_A")
			(options
				(clearance outline)
				(anchor circle)
			)
			(primitives
				(gr_poly
					(pts
						(arc
							(start -0.1778 -0.2794)
							(mid -0.249642 -0.249642)
							(end -0.2794 -0.1778)
						)
						(arc
							(start -0.2794 0.1778)
							(mid -0.249642 0.249642)
							(end -0.1778 0.2794)
						)
						(arc
							(start 0.1778 0.2794)
							(mid 0.249642 0.249642)
							(end 0.2794 0.1778)
						)
						(arc
							(start 0.2794 -0.1778)
							(mid 0.249642 -0.249642)
							(end 0.1778 -0.2794)
						)
					)
					(width 0)
					(fill yes)
				)
			)
		)
		(pad "2" smd custom
			(at 0 0.4445 90)
			(size 0.1397 0.1397)
			(layers "F.Cu" "F.Mask" "F.Paste")
			(net "SYS_RESET_BTN_A")
			(options
				(clearance outline)
				(anchor circle)
			)
			(primitives
				(gr_poly
					(pts
						(arc
							(start -0.1778 -0.2794)
							(mid -0.249642 -0.249642)
							(end -0.2794 -0.1778)
						)
						(arc
							(start -0.2794 0.1778)
							(mid -0.249642 0.249642)
							(end -0.1778 0.2794)
						)
						(arc
							(start 0.1778 0.2794)
							(mid 0.249642 0.249642)
							(end 0.2794 0.1778)
						)
						(arc
							(start 0.2794 -0.1778)
							(mid 0.249642 -0.249642)
							(end 0.1778 -0.2794)
						)
					)
					(width 0)
					(fill yes)
				)
			)
		)
	)
	(footprint ""
		(layer "F.Cu")
		(at 42.909744 -19.739102)
		(property "Reference" "R13"
			(at 0 0 0)
			(layer "F.SilkS")
			(hide yes)
			(effects
				(font
					(size 1.27 1.27)
				)
			)
		)
		(property "Value" "4K7R2F-GP"
			(at 0.064008 -4.679696 0)
			(unlocked yes)
			(layer "F.Fab")
			(hide yes)
			(effects
				(font
					(size 2.54 2.54)
					(thickness 0.381)
				)
			)
		)
		(property "Device Type" "R402H16"
			(at 0.064008 -6.203696 0)
			(unlocked yes)
			(layer "F.Fab")
			(hide yes)
			(effects
				(font
					(size 2.54 2.54)
					(thickness 0.381)
				)
			)
		)
		(duplicate_pad_numbers_are_jumpers no)
		(fp_line
			(start -0.508 -0.9398)
			(end -0.508 0.9398)
			(stroke
				(width 0.1524)
				(type default)
			)
			(layer "F.SilkS")
		)
		(fp_line
			(start 0.508 -0.9398)
			(end -0.508 -0.9398)
			(stroke
				(width 0.1524)
				(type default)
			)
			(layer "F.SilkS")
		)
		(fp_rect
			(start -0.508 0.9398)
			(end 0.508 -0.9398)
			(stroke
				(width 0)
				(type default)
			)
			(fill no)
			(layer "F.CrtYd")
		)
		(fp_rect
			(start -0.508 0.9398)
			(end 0.508 -0.9398)
			(stroke
				(width 0)
				(type default)
			)
			(fill no)
			(layer "F.Fab")
		)
		(pad "1" smd custom
			(at 0 -0.4445)
			(size 0.1397 0.1397)
			(layers "F.Cu" "F.Mask" "F.Paste")
			(net "P3V3_STBY_B")
			(options
				(clearance outline)
				(anchor circle)
			)
			(primitives
				(gr_poly
					(pts
						(arc
							(start -0.1778 -0.2794)
							(mid -0.249642 -0.249642)
							(end -0.2794 -0.1778)
						)
						(arc
							(start -0.2794 0.1778)
							(mid -0.249642 0.249642)
							(end -0.1778 0.2794)
						)
						(arc
							(start 0.1778 0.2794)
							(mid 0.249642 0.249642)
							(end 0.2794 0.1778)
						)
						(arc
							(start 0.2794 -0.1778)
							(mid 0.249642 -0.249642)
							(end 0.1778 -0.2794)
						)
					)
					(width 0)
					(fill yes)
				)
			)
		)
		(pad "2" smd custom
			(at 0 0.4445)
			(size 0.1397 0.1397)
			(layers "F.Cu" "F.Mask" "F.Paste")
			(net "I2C_DEBUG_B_SCL")
			(options
				(clearance outline)
				(anchor circle)
			)
			(primitives
				(gr_poly
					(pts
						(arc
							(start -0.1778 -0.2794)
							(mid -0.249642 -0.249642)
							(end -0.2794 -0.1778)
						)
						(arc
							(start -0.2794 0.1778)
							(mid -0.249642 0.249642)
							(end -0.1778 0.2794)
						)
						(arc
							(start 0.1778 0.2794)
							(mid 0.249642 0.249642)
							(end 0.2794 0.1778)
						)
						(arc
							(start 0.2794 -0.1778)
							(mid 0.249642 -0.249642)
							(end 0.1778 -0.2794)
						)
					)
					(width 0)
					(fill yes)
				)
			)
		)
	)
	(footprint ""
		(layer "F.Cu")
		(at 48.895 -17.399 180)
		(property "Reference" "R70"
			(at 0 0 180)
			(layer "F.SilkS")
			(hide yes)
			(effects
				(font
					(size 1.27 1.27)
				)
			)
		)
		(property "Value" "4K7R2F-GP"
			(at 0.064008 -3.993896 180)
			(unlocked yes)
			(layer "F.Fab")
			(hide yes)
			(effects
				(font
					(size 1.016 1.016)
					(thickness 0.1524)
				)
			)
		)
		(property "Device Type" "R402H16"
			(at 0.064008 -5.517896 180)
			(unlocked yes)
			(layer "F.Fab")
			(hide yes)
			(effects
				(font
					(size 1.016 1.016)
					(thickness 0.1524)
				)
			)
		)
		(duplicate_pad_numbers_are_jumpers no)
		(fp_line
			(start 0.508 -0.9398)
			(end -0.508 -0.9398)
			(stroke
				(width 0.1524)
				(type default)
			)
			(layer "F.SilkS")
		)
		(fp_line
			(start -0.508 -0.9398)
			(end -0.508 0.9398)
			(stroke
				(width 0.1524)
				(type default)
			)
			(layer "F.SilkS")
		)
		(fp_rect
			(start -0.508 0.9398)
			(end 0.508 -0.9398)
			(stroke
				(width 0)
				(type default)
			)
			(fill no)
			(layer "F.CrtYd")
		)
		(fp_rect
			(start -0.508 0.9398)
			(end 0.508 -0.9398)
			(stroke
				(width 0)
				(type default)
			)
			(fill no)
			(layer "F.Fab")
		)
		(pad "1" smd custom
			(at 0 -0.4445 180)
			(size 0.1397 0.1397)
			(layers "F.Cu" "F.Mask" "F.Paste")
			(net "TCA9555_B_A0")
			(options
				(clearance outline)
				(anchor circle)
			)
			(primitives
				(gr_poly
					(pts
						(arc
							(start -0.1778 -0.2794)
							(mid -0.249642 -0.249642)
							(end -0.2794 -0.1778)
						)
						(arc
							(start -0.2794 0.1778)
							(mid -0.249642 0.249642)
							(end -0.1778 0.2794)
						)
						(arc
							(start 0.1778 0.2794)
							(mid 0.249642 0.249642)
							(end 0.2794 0.1778)
						)
						(arc
							(start 0.2794 -0.1778)
							(mid 0.249642 -0.249642)
							(end 0.1778 -0.2794)
						)
					)
					(width 0)
					(fill yes)
				)
			)
		)
		(pad "2" smd custom
			(at 0 0.4445 180)
			(size 0.1397 0.1397)
			(layers "F.Cu" "F.Mask" "F.Paste")
			(net "GND")
			(options
				(clearance outline)
				(anchor circle)
			)
			(primitives
				(gr_poly
					(pts
						(arc
							(start -0.1778 -0.2794)
							(mid -0.249642 -0.249642)
							(end -0.2794 -0.1778)
						)
						(arc
							(start -0.2794 0.1778)
							(mid -0.249642 0.249642)
							(end -0.1778 0.2794)
						)
						(arc
							(start 0.1778 0.2794)
							(mid 0.249642 0.249642)
							(end 0.2794 0.1778)
						)
						(arc
							(start 0.2794 -0.1778)
							(mid 0.249642 -0.249642)
							(end 0.1778 -0.2794)
						)
					)
					(width 0)
					(fill yes)
				)
			)
		)
	)
)
